(kicad_pcb
	(version 20260206)
	(generator "pcbnew")
	(generator_version "10.0")
	(general
		(thickness 1.6)
		(legacy_teardrops no)
	)
	(paper "A4")
	(title_block
		(title "panther-plus-userver — 13130-1b_20150205.brd")
		(comment 1 "Honey Badger (Wiwynn) / footprint 624 of 1509 (DIMM4), pads 23-29 of 210")
	)
	(layers
		(0 "F.Cu" signal "TOP")
		(4 "In1.Cu" signal "L2")
		(6 "In2.Cu" signal "L3")
		(8 "In3.Cu" signal "L4")
		(10 "In4.Cu" signal "L5")
		(12 "In5.Cu" signal "L6")
		(14 "In6.Cu" signal "L7")
		(16 "In7.Cu" signal "L8")
		(18 "In8.Cu" signal "L9")
		(20 "In9.Cu" signal "L10")
		(22 "In10.Cu" signal "L11")
		(2 "B.Cu" signal "BOTTOM")
		(9 "F.Adhes" user "F.Adhesive")
		(11 "B.Adhes" user "B.Adhesive")
		(13 "F.Paste" user "Package Geometry/Pastemask Top")
		(15 "B.Paste" user "Package Geometry/Pastemask Bottom")
		(5 "F.SilkS" user "Ref Des/Silkscreen Top")
		(7 "B.SilkS" user "Ref Des/Silkscreen Bottom")
		(1 "F.Mask" user "Board Geometry/Soldermask Top")
		(3 "B.Mask" user "Board Geometry/Soldermask Bottom")
		(17 "Dwgs.User" user "User.Drawings")
		(19 "Cmts.User" user "User.Comments")
		(21 "Eco1.User" user "User.Eco1")
		(23 "Eco2.User" user "User.Eco2")
		(25 "Edge.Cuts" user "Board Geometry/Outline")
		(27 "Margin" user)
		(31 "F.CrtYd" user "Package Geometry/Place Bound Top")
		(29 "B.CrtYd" user "Package Geometry/Place Bound Bottom")
		(35 "F.Fab" user "Ref Des/Assembly Top")
		(33 "B.Fab" user "Ref Des/Assembly Bottom")
	)
	(footprint ""
		(layer "F.Cu")
		(at 159.999934 -5.790692)
		(property "Reference" "DIMM4"
			(at 0 0 0)
			(layer "F.SilkS")
			(hide yes)
			(effects
				(font
					(size 1.27 1.27)
				)
			)
		)
		(property "Value" "DDR3-204P-174-COLAY-1-GP"
			(at -40.682164 -17.468088 0)
			(unlocked yes)
			(layer "F.Fab")
			(hide yes)
			(effects
				(font
					(size 1.016 1.016)
					(thickness 0.1524)
				)
			)
		)
		(property "Device Type" "AS0A626-H8SN-7H-COLAY-1"
			(at -40.682164 -18.992088 0)
			(unlocked yes)
			(layer "F.Fab")
			(hide yes)
			(effects
				(font
					(size 1.016 1.016)
					(thickness 0.1524)
				)
			)
		)
		(duplicate_pad_numbers_are_jumpers no)
		(pad "21" smd custom
			(at -25.649936 4.106672)
			(size 0.1143 0.1143)
			(layers "F.Cu" "F.Mask" "F.Paste")
			(net "M_B_DQ13")
			(options
				(clearance outline)
				(anchor circle)
			)
			(primitives
				(gr_poly
					(pts
						(xy 0 0.9017) (xy -0.03175 0.89916) (xy -0.0635 0.889) (xy -0.09144 0.87376) (xy -0.11684 0.85344)
						(xy -0.13716 0.82804) (xy -0.1524 0.8001) (xy -0.16256 0.76835) (xy -0.1651 0.7366) (xy -0.1651 -0.13462)
						(xy -0.17272 -0.14224) (xy -0.19812 -0.1778) (xy -0.2032 -0.18796) (xy -0.20701 -0.19685) (xy -0.21209 -0.20701)
						(xy -0.2159 -0.21717) (xy -0.21844 -0.22733) (xy -0.22225 -0.23876) (xy -0.22352 -0.24892) (xy -0.22606 -0.25908)
						(xy -0.22733 -0.27051) (xy -0.22733 -0.28067) (xy -0.2286 -0.2921) (xy -0.22733 -0.30353) (xy -0.22733 -0.31369)
						(xy -0.22606 -0.32512) (xy -0.22352 -0.33528) (xy -0.22225 -0.34544) (xy -0.21844 -0.35687) (xy -0.2159 -0.36703)
						(xy -0.21209 -0.37719) (xy -0.20701 -0.38735) (xy -0.2032 -0.39624) (xy -0.19812 -0.4064) (xy -0.17272 -0.44196)
						(xy -0.1651 -0.44958) (xy -0.1651 -0.7366) (xy -0.16256 -0.76835) (xy -0.1524 -0.8001) (xy -0.13716 -0.82804)
						(xy -0.11684 -0.85344) (xy -0.09144 -0.87376) (xy -0.0635 -0.889) (xy -0.03175 -0.89916) (xy 0 -0.9017)
						(xy 0.03175 -0.89916) (xy 0.0635 -0.889) (xy 0.09144 -0.87376) (xy 0.11684 -0.85344) (xy 0.13716 -0.82804)
						(xy 0.1524 -0.8001) (xy 0.16256 -0.76835) (xy 0.1651 -0.7366) (xy 0.1651 -0.44958) (xy 0.17272 -0.44196)
						(xy 0.19812 -0.4064) (xy 0.2032 -0.39624) (xy 0.20701 -0.38735) (xy 0.21209 -0.37719) (xy 0.2159 -0.36703)
						(xy 0.21844 -0.35687) (xy 0.22225 -0.34544) (xy 0.22352 -0.33528) (xy 0.22606 -0.32512) (xy 0.22733 -0.31369)
						(xy 0.22733 -0.30353) (xy 0.2286 -0.2921) (xy 0.22733 -0.28067) (xy 0.22733 -0.27051) (xy 0.22606 -0.25908)
						(xy 0.22352 -0.24892) (xy 0.22225 -0.23876) (xy 0.21844 -0.22733) (xy 0.2159 -0.21717) (xy 0.21209 -0.20701)
						(xy 0.20701 -0.19685) (xy 0.2032 -0.18796) (xy 0.19812 -0.1778) (xy 0.17272 -0.14224) (xy 0.1651 -0.13462)
						(xy 0.1651 0.7366) (xy 0.16256 0.76835) (xy 0.1524 0.8001) (xy 0.13716 0.82804) (xy 0.11684 0.85344)
						(xy 0.09144 0.87376) (xy 0.0635 0.889) (xy 0.03175 0.89916)
					)
					(width 0)
					(fill yes)
				)
			)
		)
		(pad "22" smd custom
			(at -25.349962 -4.106672)
			(size 0.1143 0.1143)
			(layers "F.Cu" "F.Mask" "F.Paste")
			(net "M_B_DQ8")
			(options
				(clearance outline)
				(anchor circle)
			)
			(primitives
				(gr_poly
					(pts
						(xy 0 0.9017) (xy -0.03175 0.89916) (xy -0.0635 0.889) (xy -0.09144 0.87376) (xy -0.11684 0.85344)
						(xy -0.13716 0.82804) (xy -0.1524 0.8001) (xy -0.16256 0.76835) (xy -0.1651 0.7366) (xy -0.1651 0.44958)
						(xy -0.17272 0.44196) (xy -0.19812 0.4064) (xy -0.2032 0.39624) (xy -0.20701 0.38735) (xy -0.21209 0.37719)
						(xy -0.2159 0.36703) (xy -0.21844 0.35687) (xy -0.22225 0.34544) (xy -0.22352 0.33528) (xy -0.22606 0.32512)
						(xy -0.22733 0.31369) (xy -0.22733 0.30353) (xy -0.2286 0.2921) (xy -0.22733 0.28067) (xy -0.22733 0.27051)
						(xy -0.22606 0.25908) (xy -0.22352 0.24892) (xy -0.22225 0.23876) (xy -0.21844 0.22733) (xy -0.2159 0.21717)
						(xy -0.21209 0.20701) (xy -0.20701 0.19685) (xy -0.2032 0.18796) (xy -0.19812 0.1778) (xy -0.17272 0.14224)
						(xy -0.1651 0.13462) (xy -0.1651 -0.7366) (xy -0.16256 -0.76835) (xy -0.1524 -0.8001) (xy -0.13716 -0.82804)
						(xy -0.11684 -0.85344) (xy -0.09144 -0.87376) (xy -0.0635 -0.889) (xy -0.03175 -0.89916) (xy 0 -0.9017)
						(xy 0.03175 -0.89916) (xy 0.0635 -0.889) (xy 0.09144 -0.87376) (xy 0.11684 -0.85344) (xy 0.13716 -0.82804)
						(xy 0.1524 -0.8001) (xy 0.16256 -0.76835) (xy 0.1651 -0.7366) (xy 0.1651 0.13462) (xy 0.17272 0.14224)
						(xy 0.19812 0.1778) (xy 0.2032 0.18796) (xy 0.20701 0.19685) (xy 0.21209 0.20701) (xy 0.2159 0.21717)
						(xy 0.21844 0.22733) (xy 0.22225 0.23876) (xy 0.22352 0.24892) (xy 0.22606 0.25908) (xy 0.22733 0.27051)
						(xy 0.22733 0.28067) (xy 0.2286 0.2921) (xy 0.22733 0.30353) (xy 0.22733 0.31369) (xy 0.22606 0.32512)
						(xy 0.22352 0.33528) (xy 0.22225 0.34544) (xy 0.21844 0.35687) (xy 0.2159 0.36703) (xy 0.21209 0.37719)
						(xy 0.20701 0.38735) (xy 0.2032 0.39624) (xy 0.19812 0.4064) (xy 0.17272 0.44196) (xy 0.1651 0.44958)
						(xy 0.1651 0.7366) (xy 0.16256 0.76835) (xy 0.1524 0.8001) (xy 0.13716 0.82804) (xy 0.11684 0.85344)
						(xy 0.09144 0.87376) (xy 0.0635 0.889) (xy 0.03175 0.89916)
					)
					(width 0)
					(fill yes)
				)
			)
		)
		(pad "23" smd custom
			(at -25.049988 4.106672)
			(size 0.1143 0.1143)
			(layers "F.Cu" "F.Mask" "F.Paste")
			(net "GND")
			(options
				(clearance outline)
				(anchor circle)
			)
			(primitives
				(gr_poly
					(pts
						(xy 0 0.9017) (xy -0.03175 0.89916) (xy -0.0635 0.889) (xy -0.09144 0.87376) (xy -0.11684 0.85344)
						(xy -0.13716 0.82804) (xy -0.1524 0.8001) (xy -0.16256 0.76835) (xy -0.1651 0.7366) (xy -0.1651 0.11938)
						(xy -0.17272 0.11176) (xy -0.19812 0.0762) (xy -0.2032 0.06604) (xy -0.20701 0.05715) (xy -0.21209 0.04699)
						(xy -0.2159 0.03683) (xy -0.21844 0.02667) (xy -0.22225 0.01524) (xy -0.22352 0.00508) (xy -0.22606 -0.00508)
						(xy -0.22733 -0.01651) (xy -0.22733 -0.02667) (xy -0.2286 -0.0381) (xy -0.22733 -0.04953) (xy -0.22733 -0.05969)
						(xy -0.22606 -0.07112) (xy -0.22352 -0.08128) (xy -0.22225 -0.09144) (xy -0.21844 -0.10287) (xy -0.2159 -0.11303)
						(xy -0.21209 -0.12319) (xy -0.20701 -0.13335) (xy -0.2032 -0.14224) (xy -0.19812 -0.1524) (xy -0.17272 -0.18796)
						(xy -0.1651 -0.19558) (xy -0.1651 -0.7366) (xy -0.16256 -0.76835) (xy -0.1524 -0.8001) (xy -0.13716 -0.82804)
						(xy -0.11684 -0.85344) (xy -0.09144 -0.87376) (xy -0.0635 -0.889) (xy -0.03175 -0.89916) (xy 0 -0.9017)
						(xy 0.03175 -0.89916) (xy 0.0635 -0.889) (xy 0.09144 -0.87376) (xy 0.11684 -0.85344) (xy 0.13716 -0.82804)
						(xy 0.1524 -0.8001) (xy 0.16256 -0.76835) (xy 0.1651 -0.7366) (xy 0.1651 -0.19685) (xy 0.17272 -0.18923)
						(xy 0.17907 -0.18034) (xy 0.18669 -0.17145) (xy 0.19177 -0.16256) (xy 0.19812 -0.15367) (xy 0.20828 -0.13335)
						(xy 0.21971 -0.10287) (xy 0.22225 -0.09271) (xy 0.22479 -0.08128) (xy 0.22606 -0.07112) (xy 0.2286 -0.05969)
						(xy 0.2286 -0.01651) (xy 0.22606 -0.00508) (xy 0.22479 0.00508) (xy 0.22225 0.01651) (xy 0.21971 0.02667)
						(xy 0.20828 0.05715) (xy 0.19812 0.07747) (xy 0.19177 0.08636) (xy 0.18669 0.09525) (xy 0.17907 0.10414)
						(xy 0.17272 0.11303) (xy 0.1651 0.12065) (xy 0.1651 0.7366) (xy 0.16256 0.76835) (xy 0.1524 0.8001)
						(xy 0.13716 0.82804) (xy 0.11684 0.85344) (xy 0.09144 0.87376) (xy 0.0635 0.889) (xy 0.03175 0.89916)
					)
					(width 0)
					(fill yes)
				)
			)
		)
		(pad "24" smd custom
			(at -24.750014 -4.106672)
			(size 0.1143 0.1143)
			(layers "F.Cu" "F.Mask" "F.Paste")
			(net "M_B_DQ9")
			(options
				(clearance outline)
				(anchor circle)
			)
			(primitives
				(gr_poly
					(pts
						(xy 0 0.9017) (xy -0.03175 0.89916) (xy -0.0635 0.889) (xy -0.09144 0.87376) (xy -0.11684 0.85344)
						(xy -0.13716 0.82804) (xy -0.1524 0.8001) (xy -0.16256 0.76835) (xy -0.1651 0.7366) (xy -0.1651 0.19685)
						(xy -0.17272 0.18923) (xy -0.17907 0.18034) (xy -0.18669 0.17145) (xy -0.19177 0.16256) (xy -0.19812 0.15367)
						(xy -0.20828 0.13335) (xy -0.21971 0.10287) (xy -0.22225 0.09271) (xy -0.22479 0.08128) (xy -0.22606 0.07112)
						(xy -0.2286 0.05969) (xy -0.2286 0.01651) (xy -0.22606 0.00508) (xy -0.22479 -0.00508) (xy -0.22225 -0.01651)
						(xy -0.21971 -0.02667) (xy -0.20828 -0.05715) (xy -0.19812 -0.07747) (xy -0.19177 -0.08636) (xy -0.18669 -0.09525)
						(xy -0.17907 -0.10414) (xy -0.17272 -0.11303) (xy -0.1651 -0.12065) (xy -0.1651 -0.7366) (xy -0.16256 -0.76835)
						(xy -0.1524 -0.8001) (xy -0.13716 -0.82804) (xy -0.11684 -0.85344) (xy -0.09144 -0.87376) (xy -0.0635 -0.889)
						(xy -0.03175 -0.89916) (xy 0 -0.9017) (xy 0.03175 -0.89916) (xy 0.0635 -0.889) (xy 0.09144 -0.87376)
						(xy 0.11684 -0.85344) (xy 0.13716 -0.82804) (xy 0.1524 -0.8001) (xy 0.16256 -0.76835) (xy 0.1651 -0.7366)
						(xy 0.1651 -0.11938) (xy 0.17272 -0.11176) (xy 0.19812 -0.0762) (xy 0.2032 -0.06604) (xy 0.20701 -0.05715)
						(xy 0.21209 -0.04699) (xy 0.2159 -0.03683) (xy 0.21844 -0.02667) (xy 0.22225 -0.01524) (xy 0.22352 -0.00508)
						(xy 0.22606 0.00508) (xy 0.22733 0.01651) (xy 0.22733 0.02667) (xy 0.2286 0.0381) (xy 0.22733 0.04953)
						(xy 0.22733 0.05969) (xy 0.22606 0.07112) (xy 0.22352 0.08128) (xy 0.22225 0.09144) (xy 0.21844 0.10287)
						(xy 0.2159 0.11303) (xy 0.21209 0.12319) (xy 0.20701 0.13335) (xy 0.2032 0.14224) (xy 0.19812 0.1524)
						(xy 0.17272 0.18796) (xy 0.1651 0.19558) (xy 0.1651 0.7366) (xy 0.16256 0.76835) (xy 0.1524 0.8001)
						(xy 0.13716 0.82804) (xy 0.11684 0.85344) (xy 0.09144 0.87376) (xy 0.0635 0.889) (xy 0.03175 0.89916)
					)
					(width 0)
					(fill yes)
				)
			)
		)
		(pad "25" smd custom
			(at -24.45004 4.106672)
			(size 0.1143 0.1143)
			(layers "F.Cu" "F.Mask" "F.Paste")
			(net "M_B_DQS_DN1")
			(options
				(clearance outline)
				(anchor circle)
			)
			(primitives
				(gr_poly
					(pts
						(xy 0 0.9017) (xy -0.03175 0.89916) (xy -0.0635 0.889) (xy -0.09144 0.87376) (xy -0.11684 0.85344)
						(xy -0.13716 0.82804) (xy -0.1524 0.8001) (xy -0.16256 0.76835) (xy -0.1651 0.7366) (xy -0.1651 -0.13462)
						(xy -0.17272 -0.14224) (xy -0.19812 -0.1778) (xy -0.2032 -0.18796) (xy -0.20701 -0.19685) (xy -0.21209 -0.20701)
						(xy -0.2159 -0.21717) (xy -0.21844 -0.22733) (xy -0.22225 -0.23876) (xy -0.22352 -0.24892) (xy -0.22606 -0.25908)
						(xy -0.22733 -0.27051) (xy -0.22733 -0.28067) (xy -0.2286 -0.2921) (xy -0.22733 -0.30353) (xy -0.22733 -0.31369)
						(xy -0.22606 -0.32512) (xy -0.22352 -0.33528) (xy -0.22225 -0.34544) (xy -0.21844 -0.35687) (xy -0.2159 -0.36703)
						(xy -0.21209 -0.37719) (xy -0.20701 -0.38735) (xy -0.2032 -0.39624) (xy -0.19812 -0.4064) (xy -0.17272 -0.44196)
						(xy -0.1651 -0.44958) (xy -0.1651 -0.7366) (xy -0.16256 -0.76835) (xy -0.1524 -0.8001) (xy -0.13716 -0.82804)
						(xy -0.11684 -0.85344) (xy -0.09144 -0.87376) (xy -0.0635 -0.889) (xy -0.03175 -0.89916) (xy 0 -0.9017)
						(xy 0.03175 -0.89916) (xy 0.0635 -0.889) (xy 0.09144 -0.87376) (xy 0.11684 -0.85344) (xy 0.13716 -0.82804)
						(xy 0.1524 -0.8001) (xy 0.16256 -0.76835) (xy 0.1651 -0.7366) (xy 0.1651 -0.44958) (xy 0.17272 -0.44196)
						(xy 0.19812 -0.4064) (xy 0.2032 -0.39624) (xy 0.20701 -0.38735) (xy 0.21209 -0.37719) (xy 0.2159 -0.36703)
						(xy 0.21844 -0.35687) (xy 0.22225 -0.34544) (xy 0.22352 -0.33528) (xy 0.22606 -0.32512) (xy 0.22733 -0.31369)
						(xy 0.22733 -0.30353) (xy 0.2286 -0.2921) (xy 0.22733 -0.28067) (xy 0.22733 -0.27051) (xy 0.22606 -0.25908)
						(xy 0.22352 -0.24892) (xy 0.22225 -0.23876) (xy 0.21844 -0.22733) (xy 0.2159 -0.21717) (xy 0.21209 -0.20701)
						(xy 0.20701 -0.19685) (xy 0.2032 -0.18796) (xy 0.19812 -0.1778) (xy 0.17272 -0.14224) (xy 0.1651 -0.13462)
						(xy 0.1651 0.7366) (xy 0.16256 0.76835) (xy 0.1524 0.8001) (xy 0.13716 0.82804) (xy 0.11684 0.85344)
						(xy 0.09144 0.87376) (xy 0.0635 0.889) (xy 0.03175 0.89916)
					)
					(width 0)
					(fill yes)
				)
			)
		)
		(pad "26" smd custom
			(at -24.150066 -4.106672)
			(size 0.1143 0.1143)
			(layers "F.Cu" "F.Mask" "F.Paste")
			(net "GND")
			(options
				(clearance outline)
				(anchor circle)
			)
			(primitives
				(gr_poly
					(pts
						(xy 0 0.9017) (xy -0.03175 0.89916) (xy -0.0635 0.889) (xy -0.09144 0.87376) (xy -0.11684 0.85344)
						(xy -0.13716 0.82804) (xy -0.1524 0.8001) (xy -0.16256 0.76835) (xy -0.1651 0.7366) (xy -0.1651 0.44958)
						(xy -0.17272 0.44196) (xy -0.19812 0.4064) (xy -0.2032 0.39624) (xy -0.20701 0.38735) (xy -0.21209 0.37719)
						(xy -0.2159 0.36703) (xy -0.21844 0.35687) (xy -0.22225 0.34544) (xy -0.22352 0.33528) (xy -0.22606 0.32512)
						(xy -0.22733 0.31369) (xy -0.22733 0.30353) (xy -0.2286 0.2921) (xy -0.22733 0.28067) (xy -0.22733 0.27051)
						(xy -0.22606 0.25908) (xy -0.22352 0.24892) (xy -0.22225 0.23876) (xy -0.21844 0.22733) (xy -0.2159 0.21717)
						(xy -0.21209 0.20701) (xy -0.20701 0.19685) (xy -0.2032 0.18796) (xy -0.19812 0.1778) (xy -0.17272 0.14224)
						(xy -0.1651 0.13462) (xy -0.1651 -0.7366) (xy -0.16256 -0.76835) (xy -0.1524 -0.8001) (xy -0.13716 -0.82804)
						(xy -0.11684 -0.85344) (xy -0.09144 -0.87376) (xy -0.0635 -0.889) (xy -0.03175 -0.89916) (xy 0 -0.9017)
						(xy 0.03175 -0.89916) (xy 0.0635 -0.889) (xy 0.09144 -0.87376) (xy 0.11684 -0.85344) (xy 0.13716 -0.82804)
						(xy 0.1524 -0.8001) (xy 0.16256 -0.76835) (xy 0.1651 -0.7366) (xy 0.1651 0.13462) (xy 0.17272 0.14224)
						(xy 0.19812 0.1778) (xy 0.2032 0.18796) (xy 0.20701 0.19685) (xy 0.21209 0.20701) (xy 0.2159 0.21717)
						(xy 0.21844 0.22733) (xy 0.22225 0.23876) (xy 0.22352 0.24892) (xy 0.22606 0.25908) (xy 0.22733 0.27051)
						(xy 0.22733 0.28067) (xy 0.2286 0.2921) (xy 0.22733 0.30353) (xy 0.22733 0.31369) (xy 0.22606 0.32512)
						(xy 0.22352 0.33528) (xy 0.22225 0.34544) (xy 0.21844 0.35687) (xy 0.2159 0.36703) (xy 0.21209 0.37719)
						(xy 0.20701 0.38735) (xy 0.2032 0.39624) (xy 0.19812 0.4064) (xy 0.17272 0.44196) (xy 0.1651 0.44958)
						(xy 0.1651 0.7366) (xy 0.16256 0.76835) (xy 0.1524 0.8001) (xy 0.13716 0.82804) (xy 0.11684 0.85344)
						(xy 0.09144 0.87376) (xy 0.0635 0.889) (xy 0.03175 0.89916)
					)
					(width 0)
					(fill yes)
				)
			)
		)
		(pad "27" smd custom
			(at -23.850092 4.106672)
			(size 0.1143 0.1143)
			(layers "F.Cu" "F.Mask" "F.Paste")
			(net "M_B_DQS_DP1")
			(options
				(clearance outline)
				(anchor circle)
			)
			(primitives
				(gr_poly
					(pts
						(xy 0 0.9017) (xy -0.03175 0.89916) (xy -0.0635 0.889) (xy -0.09144 0.87376) (xy -0.11684 0.85344)
						(xy -0.13716 0.82804) (xy -0.1524 0.8001) (xy -0.16256 0.76835) (xy -0.1651 0.7366) (xy -0.1651 0.11938)
						(xy -0.17272 0.11176) (xy -0.19812 0.0762) (xy -0.2032 0.06604) (xy -0.20701 0.05715) (xy -0.21209 0.04699)
						(xy -0.2159 0.03683) (xy -0.21844 0.02667) (xy -0.22225 0.01524) (xy -0.22352 0.00508) (xy -0.22606 -0.00508)
						(xy -0.22733 -0.01651) (xy -0.22733 -0.02667) (xy -0.2286 -0.0381) (xy -0.22733 -0.04953) (xy -0.22733 -0.05969)
						(xy -0.22606 -0.07112) (xy -0.22352 -0.08128) (xy -0.22225 -0.09144) (xy -0.21844 -0.10287) (xy -0.2159 -0.11303)
						(xy -0.21209 -0.12319) (xy -0.20701 -0.13335) (xy -0.2032 -0.14224) (xy -0.19812 -0.1524) (xy -0.17272 -0.18796)
						(xy -0.1651 -0.19558) (xy -0.1651 -0.7366) (xy -0.16256 -0.76835) (xy -0.1524 -0.8001) (xy -0.13716 -0.82804)
						(xy -0.11684 -0.85344) (xy -0.09144 -0.87376) (xy -0.0635 -0.889) (xy -0.03175 -0.89916) (xy 0 -0.9017)
						(xy 0.03175 -0.89916) (xy 0.0635 -0.889) (xy 0.09144 -0.87376) (xy 0.11684 -0.85344) (xy 0.13716 -0.82804)
						(xy 0.1524 -0.8001) (xy 0.16256 -0.76835) (xy 0.1651 -0.7366) (xy 0.1651 -0.19685) (xy 0.17272 -0.18923)
						(xy 0.17907 -0.18034) (xy 0.18669 -0.17145) (xy 0.19177 -0.16256) (xy 0.19812 -0.15367) (xy 0.20828 -0.13335)
						(xy 0.21971 -0.10287) (xy 0.22225 -0.09271) (xy 0.22479 -0.08128) (xy 0.22606 -0.07112) (xy 0.2286 -0.05969)
						(xy 0.2286 -0.01651) (xy 0.22606 -0.00508) (xy 0.22479 0.00508) (xy 0.22225 0.01651) (xy 0.21971 0.02667)
						(xy 0.20828 0.05715) (xy 0.19812 0.07747) (xy 0.19177 0.08636) (xy 0.18669 0.09525) (xy 0.17907 0.10414)
						(xy 0.17272 0.11303) (xy 0.1651 0.12065) (xy 0.1651 0.7366) (xy 0.16256 0.76835) (xy 0.1524 0.8001)
						(xy 0.13716 0.82804) (xy 0.11684 0.85344) (xy 0.09144 0.87376) (xy 0.0635 0.889) (xy 0.03175 0.89916)
					)
					(width 0)
					(fill yes)
				)
			)
		)
	)
)
